FILE_TYPE = MACRO_DRAWING;
SET COLOR_WIRE YELLOW;
SET COLOR_PROP ORANGE;
SET COLOR_DOT WHITE;
SET COLOR_ARC YELLOW;
SET COLOR_BODY GREEN;
SET COLOR_NOTE PURPLE;
SET PROP_DISPLAY VALUE;
SET PAGE_NUMBER P204;
FORCEADD QUANTA_TITLE_BLOCK_C..1
(4700 -1775);
FORCEPROP 1 LAST CUSTOM_TXT_CDS <NAME_2>
J 0
(1525 -1725);
FORCEPROP 1 LAST CUSTOM_TXT_CDS <NAME_1>
J 0
(1525 -1600);
FORCEPROP 1 LAST CUSTOM_TXT_CDS <Q_NUMBER>
J 0
(3297 -1672);
DISPLAY 1.212766 (3297 -1672);
FORCEPROP 1 LAST CUSTOM_TXT_CDS <Q_PROJ>
J 0
(2318 -1673);
DISPLAY 1.212766 (2318 -1673);
FORCEPROP 1 LAST CUSTOM_TXT_CDS <Q_REV>
J 0
(4516 -1672);
DISPLAY 1.212766 (4516 -1672);
FORCEPROP 1 LAST CUSTOM_TXT_CDS <CON_LAST_MODIFIED>
J 0
(2815 -1760);
DISPLAY 0.978723 (2815 -1760);
FORCEPROP 1 LAST CUSTOM_TXT_CDS <CON_PAGE_NUM> OF <CON_TOTAL_PAGES>
J 0
(4254 -1757);
DISPLAY 0.978723 (4254 -1757);
FORCEPROP 1 LAST Q_TITLE eFUSE - E1S_1
J 0
(-4600 -1725);
DISPLAY 2.446809 (-4600 -1725);
PAINT GREEN (-4600 -1725);
FORCEPROP 1 LAST Q_DEPT BU9
J 1
(937 -1726);
DISPLAY 1.957447 (937 -1726);
PAINT GREEN (937 -1726);
FORCEPROP 2 LAST PAGE_BORDER TRUE
J 0
(-3190 3475);
DISPLAY 0.638298 (-3190 3475);
PAINT PINK (-3190 3475);
DISPLAY INVISIBLE (-3190 3475);
FORCEPROP 1 LAST CDS_LMAN_SYM_OUTLINE -9475,6775,100,-125
J 0
(4700 -1775);
DISPLAY 0.468085 (4700 -1775);
PAINT GREEN (4700 -1775);
DISPLAY INVISIBLE (4700 -1775);
FORCEPROP 2 LAST CDS_LIB pure_quanta
J 0
(4700 -1775);
DISPLAY INVISIBLE (4700 -1775);
FORCEPROP 1 LAST COMMENT_BODY TRUE
J 0
(4712 -1788);
DISPLAY 0.978723 (4712 -1788);
PAINT GREEN (4712 -1788);
DISPLAY INVISIBLE (4712 -1788);
FORCEPROP 2 LAST CDS_XR_PAGE_TITLE CR-205 : @T6G_MB_LIB.T6G(SCH_1):PAGE205
J 0
(-3190 3475);
DISPLAY 0.638298 (-3190 3475);
PAINT PINK (-3190 3475);
DISPLAY INVISIBLE (-3190 3475);
FORCEPROP 2 LAST CUSTOM_TXT_CDS <XR_PAGE_TITLE>
J 0
(-3190 3475);
DISPLAY 0.638298 (-3190 3475);
PAINT PINK (-3190 3475);
DISPLAY INVISIBLE (-3190 3475);
FORCEPROP 0 LAST CDS_CON_LAST_MODIFIED Wed Mar 09 21:44:36 2022
J 0
(2815 -1760);
DISPLAY INVISIBLE (2815 -1760);
QUIT
